(kicad_pcb
	(version 20260206)
	(generator "pcbnew")
	(generator_version "10.0")
	(general
		(thickness 1.6)
		(legacy_teardrops no)
	)
	(paper "A4")
	(title_block
		(title "04192023_DAF0TMB3IC0_F0TG_MB_C_brd_V02_OCP.brd")
		(comment 1 "Grand Teton / footprints 6397-6404 of 8354")
	)
	(layers
		(0 "F.Cu" signal "TOP")
		(4 "In1.Cu" signal "GND")
		(6 "In2.Cu" signal "IN1")
		(8 "In3.Cu" signal "GND1")
		(10 "In4.Cu" signal "IN2")
		(12 "In5.Cu" signal "GND2")
		(14 "In6.Cu" signal "IN3")
		(16 "In7.Cu" signal "GND3")
		(18 "In8.Cu" signal "VCC")
		(20 "In9.Cu" signal "VCC1")
		(22 "In10.Cu" signal "GND4")
		(24 "In11.Cu" signal "IN4")
		(26 "In12.Cu" signal "GND5")
		(28 "In13.Cu" signal "IN5")
		(30 "In14.Cu" signal "GND6")
		(32 "In15.Cu" signal "IN6")
		(34 "In16.Cu" signal "GND7")
		(2 "B.Cu" signal "BOTTOM")
		(9 "F.Adhes" user "F.Adhesive")
		(11 "B.Adhes" user "B.Adhesive")
		(13 "F.Paste" user "Package Geometry/Pastemask Top")
		(15 "B.Paste" user "Package Geometry/Pastemask Bottom")
		(5 "F.SilkS" user "Ref Des/Silkscreen Top")
		(7 "B.SilkS" user "Ref Des/Silkscreen Bottom")
		(1 "F.Mask" user "Board Geometry/Soldermask Top")
		(3 "B.Mask" user "Board Geometry/Soldermask Bottom")
		(17 "Dwgs.User" user "User.Drawings")
		(19 "Cmts.User" user "User.Comments")
		(21 "Eco1.User" user "User.Eco1")
		(23 "Eco2.User" user "User.Eco2")
		(25 "Edge.Cuts" user "Board Geometry/Outline")
		(27 "Margin" user)
		(31 "F.CrtYd" user "Package Geometry/Place Bound Top")
		(29 "B.CrtYd" user "Package Geometry/Place Bound Bottom")
		(35 "F.Fab" user "Ref Des/Assembly Top")
		(33 "B.Fab" user "Ref Des/Assembly Bottom")
	)
	(footprint ""
		(layer "B.Cu")
		(at 239.903 -338.455)
		(property "Reference" "R1399"
			(at 0 0 0)
			(layer "B.SilkS")
			(hide yes)
			(effects
				(font
					(size 1.27 1.27)
				)
				(justify mirror)
			)
		)
		(property "Value" ""
			(at 0 0 0)
			(layer "B.Fab")
			(effects
				(font
					(size 1.27 1.27)
				)
				(justify mirror)
			)
		)
		(duplicate_pad_numbers_are_jumpers no)
		(fp_line
			(start -0.32512 -0.175006)
			(end -0.32512 0.175006)
			(stroke
				(width 0.1)
				(type default)
			)
			(layer "B.Fab")
		)
		(fp_line
			(start -0.32512 0.175006)
			(end 0.32512 0.175006)
			(stroke
				(width 0.1)
				(type default)
			)
			(layer "B.Fab")
		)
		(fp_line
			(start 0.32512 -0.175006)
			(end -0.32512 -0.175006)
			(stroke
				(width 0.1)
				(type default)
			)
			(layer "B.Fab")
		)
		(fp_line
			(start 0.32512 0.175006)
			(end 0.32512 -0.175006)
			(stroke
				(width 0.1)
				(type default)
			)
			(layer "B.Fab")
		)
		(pad "1" smd rect
			(at 0.2667 0 180)
			(size 0.3048 0.381)
			(layers "B.Cu" "B.Mask" "B.Paste")
			(net "P1V8_CPU1_RT_1D")
		)
		(pad "2" smd rect
			(at -0.2667 0)
			(size 0.3048 0.381)
			(layers "B.Cu" "B.Mask" "B.Paste")
			(net "SMB_RT_CPU1_P3_ROM_MUX_2D_R_SDA")
		)
	)
	(footprint ""
		(layer "B.Cu")
		(at 241.140488 -332.613 180)
		(property "Reference" "R848"
			(at 0 0 0)
			(layer "B.SilkS")
			(hide yes)
			(effects
				(font
					(size 1.27 1.27)
				)
				(justify mirror)
			)
		)
		(property "Value" ""
			(at 0 0 0)
			(layer "B.Fab")
			(effects
				(font
					(size 1.27 1.27)
				)
				(justify mirror)
			)
		)
		(duplicate_pad_numbers_are_jumpers no)
		(fp_line
			(start 0.32512 0.175006)
			(end 0.32512 -0.175006)
			(stroke
				(width 0.1)
				(type default)
			)
			(layer "B.Fab")
		)
		(fp_line
			(start 0.32512 -0.175006)
			(end -0.32512 -0.175006)
			(stroke
				(width 0.1)
				(type default)
			)
			(layer "B.Fab")
		)
		(fp_line
			(start -0.32512 0.175006)
			(end 0.32512 0.175006)
			(stroke
				(width 0.1)
				(type default)
			)
			(layer "B.Fab")
		)
		(fp_line
			(start -0.32512 -0.175006)
			(end -0.32512 0.175006)
			(stroke
				(width 0.1)
				(type default)
			)
			(layer "B.Fab")
		)
		(pad "1" smd rect
			(at 0.2667 0)
			(size 0.3048 0.381)
			(layers "B.Cu" "B.Mask" "B.Paste")
			(net "RST_SMB_RT_ROM_R1_N")
		)
		(pad "2" smd rect
			(at -0.2667 0 180)
			(size 0.3048 0.381)
			(layers "B.Cu" "B.Mask" "B.Paste")
			(net "RST_SMB_RT_ROM_N")
		)
	)
	(footprint ""
		(layer "B.Cu")
		(at 208.461356 -387.676136)
		(property "Reference" "PR2514"
			(at 0 0 0)
			(layer "B.SilkS")
			(hide yes)
			(effects
				(font
					(size 1.27 1.27)
				)
				(justify mirror)
			)
		)
		(property "Value" ""
			(at 0 0 0)
			(layer "B.Fab")
			(effects
				(font
					(size 1.27 1.27)
				)
				(justify mirror)
			)
		)
		(duplicate_pad_numbers_are_jumpers no)
		(fp_line
			(start -0.7874 -0.4064)
			(end -0.7874 0.4064)
			(stroke
				(width 0.1524)
				(type default)
			)
			(layer "B.SilkS")
		)
		(fp_line
			(start -0.7874 0.4064)
			(end 0.7874 0.4064)
			(stroke
				(width 0.1524)
				(type default)
			)
			(layer "B.SilkS")
		)
		(fp_line
			(start 0.7874 -0.4064)
			(end -0.7874 -0.4064)
			(stroke
				(width 0.1524)
				(type default)
			)
			(layer "B.SilkS")
		)
		(fp_line
			(start 0.7874 0.4064)
			(end 0.7874 -0.4064)
			(stroke
				(width 0.1524)
				(type default)
			)
			(layer "B.SilkS")
		)
		(fp_line
			(start -0.67945 -0.3048)
			(end -0.67945 0.3048)
			(stroke
				(width 0.1)
				(type default)
			)
			(layer "B.Fab")
		)
		(fp_line
			(start -0.67945 0.3048)
			(end -0.120396 0.3048)
			(stroke
				(width 0.1)
				(type default)
			)
			(layer "B.Fab")
		)
		(fp_line
			(start -0.12065 -0.3048)
			(end -0.67945 -0.3048)
			(stroke
				(width 0.1)
				(type default)
			)
			(layer "B.Fab")
		)
		(fp_line
			(start -0.12065 -0.2794)
			(end -0.12065 -0.3048)
			(stroke
				(width 0.1)
				(type default)
			)
			(layer "B.Fab")
		)
		(fp_line
			(start -0.120396 0.2794)
			(end 0.12065 0.2794)
			(stroke
				(width 0.1)
				(type default)
			)
			(layer "B.Fab")
		)
		(fp_line
			(start -0.120396 0.3048)
			(end -0.120396 0.2794)
			(stroke
				(width 0.1)
				(type default)
			)
			(layer "B.Fab")
		)
		(fp_line
			(start 0.12065 -0.305054)
			(end 0.12065 -0.2794)
			(stroke
				(width 0.1)
				(type default)
			)
			(layer "B.Fab")
		)
		(fp_line
			(start 0.12065 -0.2794)
			(end -0.12065 -0.2794)
			(stroke
				(width 0.1)
				(type default)
			)
			(layer "B.Fab")
		)
		(fp_line
			(start 0.12065 0.2794)
			(end 0.12065 0.3048)
			(stroke
				(width 0.1)
				(type default)
			)
			(layer "B.Fab")
		)
		(fp_line
			(start 0.12065 0.3048)
			(end 0.67945 0.3048)
			(stroke
				(width 0.1)
				(type default)
			)
			(layer "B.Fab")
		)
		(fp_line
			(start 0.67945 -0.305054)
			(end 0.12065 -0.305054)
			(stroke
				(width 0.1)
				(type default)
			)
			(layer "B.Fab")
		)
		(fp_line
			(start 0.67945 0.3048)
			(end 0.67945 -0.305054)
			(stroke
				(width 0.1)
				(type default)
			)
			(layer "B.Fab")
		)
		(pad "1" smd circle
			(at 0.40005 0 180)
			(size 0 0)
			(layers "B.Cu" "B.Mask" "B.Paste")
			(net "P12V_HSC_ADC_P")
		)
		(pad "2" smd circle
			(at -0.40005 0 180)
			(size 0 0)
			(layers "B.Cu" "B.Mask" "B.Paste")
			(net "P12V_HSC_SENSE1_P")
		)
	)
	(footprint ""
		(layer "B.Cu")
		(at 164.266626 -109.076998 90)
		(property "Reference" "R25"
			(at 0 0 90)
			(layer "B.SilkS")
			(hide yes)
			(effects
				(font
					(size 1.27 1.27)
				)
				(justify mirror)
			)
		)
		(property "Value" ""
			(at 0 0 90)
			(layer "B.Fab")
			(effects
				(font
					(size 1.27 1.27)
				)
				(justify mirror)
			)
		)
		(duplicate_pad_numbers_are_jumpers no)
		(fp_line
			(start 0.7874 -0.4064)
			(end -0.7874 -0.4064)
			(stroke
				(width 0.1524)
				(type default)
			)
			(layer "B.SilkS")
		)
		(fp_line
			(start -0.7874 -0.4064)
			(end -0.7874 0.4064)
			(stroke
				(width 0.1524)
				(type default)
			)
			(layer "B.SilkS")
		)
		(fp_line
			(start 0.7874 0.4064)
			(end 0.7874 -0.4064)
			(stroke
				(width 0.1524)
				(type default)
			)
			(layer "B.SilkS")
		)
		(fp_line
			(start -0.7874 0.4064)
			(end 0.7874 0.4064)
			(stroke
				(width 0.1524)
				(type default)
			)
			(layer "B.SilkS")
		)
		(fp_line
			(start 0.67945 -0.305054)
			(end 0.12065 -0.305054)
			(stroke
				(width 0.1)
				(type default)
			)
			(layer "B.Fab")
		)
		(fp_line
			(start 0.12065 -0.305054)
			(end 0.12065 -0.2794)
			(stroke
				(width 0.1)
				(type default)
			)
			(layer "B.Fab")
		)
		(fp_line
			(start -0.12065 -0.3048)
			(end -0.67945 -0.3048)
			(stroke
				(width 0.1)
				(type default)
			)
			(layer "B.Fab")
		)
		(fp_line
			(start -0.67945 -0.3048)
			(end -0.67945 0.3048)
			(stroke
				(width 0.1)
				(type default)
			)
			(layer "B.Fab")
		)
		(fp_line
			(start 0.12065 -0.2794)
			(end -0.12065 -0.2794)
			(stroke
				(width 0.1)
				(type default)
			)
			(layer "B.Fab")
		)
		(fp_line
			(start -0.12065 -0.2794)
			(end -0.12065 -0.3048)
			(stroke
				(width 0.1)
				(type default)
			)
			(layer "B.Fab")
		)
		(fp_line
			(start 0.12065 0.2794)
			(end 0.12065 0.3048)
			(stroke
				(width 0.1)
				(type default)
			)
			(layer "B.Fab")
		)
		(fp_line
			(start -0.120396 0.2794)
			(end 0.12065 0.2794)
			(stroke
				(width 0.1)
				(type default)
			)
			(layer "B.Fab")
		)
		(fp_line
			(start 0.67945 0.3048)
			(end 0.67945 -0.305054)
			(stroke
				(width 0.1)
				(type default)
			)
			(layer "B.Fab")
		)
		(fp_line
			(start 0.12065 0.3048)
			(end 0.67945 0.3048)
			(stroke
				(width 0.1)
				(type default)
			)
			(layer "B.Fab")
		)
		(fp_line
			(start -0.120396 0.3048)
			(end -0.120396 0.2794)
			(stroke
				(width 0.1)
				(type default)
			)
			(layer "B.Fab")
		)
		(fp_line
			(start -0.67945 0.3048)
			(end -0.120396 0.3048)
			(stroke
				(width 0.1)
				(type default)
			)
			(layer "B.Fab")
		)
		(pad "1" smd circle
			(at 0.40005 0 270)
			(size 0 0)
			(layers "B.Cu" "B.Mask" "B.Paste")
			(net "FM_I3C_CPU1_MUX1_OE_N")
		)
		(pad "2" smd circle
			(at -0.40005 0 270)
			(size 0 0)
			(layers "B.Cu" "B.Mask" "B.Paste")
			(net "GND")
		)
	)
	(footprint ""
		(layer "B.Cu")
		(at 43.265852 -385.09956 180)
		(property "Reference" "R720"
			(at 0 0 0)
			(layer "B.SilkS")
			(hide yes)
			(effects
				(font
					(size 1.27 1.27)
				)
				(justify mirror)
			)
		)
		(property "Value" ""
			(at 0 0 0)
			(layer "B.Fab")
			(effects
				(font
					(size 1.27 1.27)
				)
				(justify mirror)
			)
		)
		(duplicate_pad_numbers_are_jumpers no)
		(fp_line
			(start 0.32512 0.175006)
			(end 0.32512 -0.175006)
			(stroke
				(width 0.1)
				(type default)
			)
			(layer "B.Fab")
		)
		(fp_line
			(start 0.32512 -0.175006)
			(end -0.32512 -0.175006)
			(stroke
				(width 0.1)
				(type default)
			)
			(layer "B.Fab")
		)
		(fp_line
			(start -0.32512 0.175006)
			(end 0.32512 0.175006)
			(stroke
				(width 0.1)
				(type default)
			)
			(layer "B.Fab")
		)
		(fp_line
			(start -0.32512 -0.175006)
			(end -0.32512 0.175006)
			(stroke
				(width 0.1)
				(type default)
			)
			(layer "B.Fab")
		)
		(pad "1" smd rect
			(at 0.2667 0)
			(size 0.3048 0.381)
			(layers "B.Cu" "B.Mask" "B.Paste")
			(net "P1V8_CPU1_RT_1D")
		)
		(pad "2" smd rect
			(at -0.2667 0 180)
			(size 0.3048 0.381)
			(layers "B.Cu" "B.Mask" "B.Paste")
			(net "TEST1_RT_CPU1_P0")
		)
	)
	(footprint ""
		(layer "B.Cu")
		(at 114.325908 -256.012442 -90)
		(property "Reference" "C3907"
			(at 0 0 90)
			(layer "B.SilkS")
			(hide yes)
			(effects
				(font
					(size 1.27 1.27)
				)
				(justify mirror)
			)
		)
		(property "Value" ""
			(at 0 0 90)
			(layer "B.Fab")
			(effects
				(font
					(size 1.27 1.27)
				)
				(justify mirror)
			)
		)
		(duplicate_pad_numbers_are_jumpers no)
		(fp_line
			(start -0.7874 0.4064)
			(end 0.7874 0.4064)
			(stroke
				(width 0.1524)
				(type default)
			)
			(layer "B.SilkS")
		)
		(fp_line
			(start 0.7874 0.4064)
			(end 0.7874 -0.4064)
			(stroke
				(width 0.1524)
				(type default)
			)
			(layer "B.SilkS")
		)
		(fp_line
			(start -0.7874 -0.4064)
			(end -0.7874 0.4064)
			(stroke
				(width 0.1524)
				(type default)
			)
			(layer "B.SilkS")
		)
		(fp_line
			(start 0.7874 -0.4064)
			(end -0.7874 -0.4064)
			(stroke
				(width 0.1524)
				(type default)
			)
			(layer "B.SilkS")
		)
		(fp_line
			(start -0.67945 0.3048)
			(end -0.120396 0.3048)
			(stroke
				(width 0.1)
				(type default)
			)
			(layer "B.Fab")
		)
		(fp_line
			(start -0.120396 0.3048)
			(end -0.120396 0.2794)
			(stroke
				(width 0.1)
				(type default)
			)
			(layer "B.Fab")
		)
		(fp_line
			(start 0.12065 0.3048)
			(end 0.67945 0.3048)
			(stroke
				(width 0.1)
				(type default)
			)
			(layer "B.Fab")
		)
		(fp_line
			(start 0.67945 0.3048)
			(end 0.67945 -0.305054)
			(stroke
				(width 0.1)
				(type default)
			)
			(layer "B.Fab")
		)
		(fp_line
			(start -0.120396 0.2794)
			(end 0.12065 0.2794)
			(stroke
				(width 0.1)
				(type default)
			)
			(layer "B.Fab")
		)
		(fp_line
			(start 0.12065 0.2794)
			(end 0.12065 0.3048)
			(stroke
				(width 0.1)
				(type default)
			)
			(layer "B.Fab")
		)
		(fp_line
			(start -0.12065 -0.2794)
			(end -0.12065 -0.3048)
			(stroke
				(width 0.1)
				(type default)
			)
			(layer "B.Fab")
		)
		(fp_line
			(start 0.12065 -0.2794)
			(end -0.12065 -0.2794)
			(stroke
				(width 0.1)
				(type default)
			)
			(layer "B.Fab")
		)
		(fp_line
			(start -0.67945 -0.3048)
			(end -0.67945 0.3048)
			(stroke
				(width 0.1)
				(type default)
			)
			(layer "B.Fab")
		)
		(fp_line
			(start -0.12065 -0.3048)
			(end -0.67945 -0.3048)
			(stroke
				(width 0.1)
				(type default)
			)
			(layer "B.Fab")
		)
		(fp_line
			(start 0.12065 -0.305054)
			(end 0.12065 -0.2794)
			(stroke
				(width 0.1)
				(type default)
			)
			(layer "B.Fab")
		)
		(fp_line
			(start 0.67945 -0.305054)
			(end 0.12065 -0.305054)
			(stroke
				(width 0.1)
				(type default)
			)
			(layer "B.Fab")
		)
		(pad "1" smd circle
			(at 0.40005 0 90)
			(size 0 0)
			(layers "B.Cu" "B.Mask" "B.Paste")
			(net "PVDDCR_SOC_P1")
		)
		(pad "2" smd circle
			(at -0.40005 0 90)
			(size 0 0)
			(layers "B.Cu" "B.Mask" "B.Paste")
			(net "GND")
		)
	)
	(footprint ""
		(layer "B.Cu")
		(at 352.501454 -264.35431)
		(property "Reference" "C2608"
			(at 0 0 0)
			(layer "B.SilkS")
			(hide yes)
			(effects
				(font
					(size 1.27 1.27)
				)
				(justify mirror)
			)
		)
		(property "Value" ""
			(at 0 0 0)
			(layer "B.Fab")
			(effects
				(font
					(size 1.27 1.27)
				)
				(justify mirror)
			)
		)
		(duplicate_pad_numbers_are_jumpers no)
		(fp_line
			(start -0.7874 -0.4064)
			(end -0.7874 0.4064)
			(stroke
				(width 0.1524)
				(type default)
			)
			(layer "B.SilkS")
		)
		(fp_line
			(start -0.7874 0.4064)
			(end 0.7874 0.4064)
			(stroke
				(width 0.1524)
				(type default)
			)
			(layer "B.SilkS")
		)
		(fp_line
			(start 0.7874 -0.4064)
			(end -0.7874 -0.4064)
			(stroke
				(width 0.1524)
				(type default)
			)
			(layer "B.SilkS")
		)
		(fp_line
			(start 0.7874 0.4064)
			(end 0.7874 -0.4064)
			(stroke
				(width 0.1524)
				(type default)
			)
			(layer "B.SilkS")
		)
		(fp_line
			(start -0.67945 -0.3048)
			(end -0.67945 0.3048)
			(stroke
				(width 0.1)
				(type default)
			)
			(layer "B.Fab")
		)
		(fp_line
			(start -0.67945 0.3048)
			(end -0.120396 0.3048)
			(stroke
				(width 0.1)
				(type default)
			)
			(layer "B.Fab")
		)
		(fp_line
			(start -0.12065 -0.3048)
			(end -0.67945 -0.3048)
			(stroke
				(width 0.1)
				(type default)
			)
			(layer "B.Fab")
		)
		(fp_line
			(start -0.12065 -0.2794)
			(end -0.12065 -0.3048)
			(stroke
				(width 0.1)
				(type default)
			)
			(layer "B.Fab")
		)
		(fp_line
			(start -0.120396 0.2794)
			(end 0.12065 0.2794)
			(stroke
				(width 0.1)
				(type default)
			)
			(layer "B.Fab")
		)
		(fp_line
			(start -0.120396 0.3048)
			(end -0.120396 0.2794)
			(stroke
				(width 0.1)
				(type default)
			)
			(layer "B.Fab")
		)
		(fp_line
			(start 0.12065 -0.305054)
			(end 0.12065 -0.2794)
			(stroke
				(width 0.1)
				(type default)
			)
			(layer "B.Fab")
		)
		(fp_line
			(start 0.12065 -0.2794)
			(end -0.12065 -0.2794)
			(stroke
				(width 0.1)
				(type default)
			)
			(layer "B.Fab")
		)
		(fp_line
			(start 0.12065 0.2794)
			(end 0.12065 0.3048)
			(stroke
				(width 0.1)
				(type default)
			)
			(layer "B.Fab")
		)
		(fp_line
			(start 0.12065 0.3048)
			(end 0.67945 0.3048)
			(stroke
				(width 0.1)
				(type default)
			)
			(layer "B.Fab")
		)
		(fp_line
			(start 0.67945 -0.305054)
			(end 0.12065 -0.305054)
			(stroke
				(width 0.1)
				(type default)
			)
			(layer "B.Fab")
		)
		(fp_line
			(start 0.67945 0.3048)
			(end 0.67945 -0.305054)
			(stroke
				(width 0.1)
				(type default)
			)
			(layer "B.Fab")
		)
		(pad "1" smd circle
			(at 0.40005 0 180)
			(size 0 0)
			(layers "B.Cu" "B.Mask" "B.Paste")
			(net "PVDD11_S3_P0")
		)
		(pad "2" smd circle
			(at -0.40005 0 180)
			(size 0 0)
			(layers "B.Cu" "B.Mask" "B.Paste")
			(net "GND")
		)
	)
	(footprint ""
		(layer "B.Cu")
		(at 124.091192 -390.560052 90)
		(property "Reference" "C437"
			(at 0 0 90)
			(layer "B.SilkS")
			(hide yes)
			(effects
				(font
					(size 1.27 1.27)
				)
				(justify mirror)
			)
		)
		(property "Value" ""
			(at 0 0 90)
			(layer "B.Fab")
			(effects
				(font
					(size 1.27 1.27)
				)
				(justify mirror)
			)
		)
		(duplicate_pad_numbers_are_jumpers no)
		(fp_line
			(start 0.7874 -0.4064)
			(end -0.7874 -0.4064)
			(stroke
				(width 0.1524)
				(type default)
			)
			(layer "B.SilkS")
		)
		(fp_line
			(start -0.7874 -0.4064)
			(end -0.7874 0.4064)
			(stroke
				(width 0.1524)
				(type default)
			)
			(layer "B.SilkS")
		)
		(fp_line
			(start 0.7874 0.4064)
			(end 0.7874 -0.4064)
			(stroke
				(width 0.1524)
				(type default)
			)
			(layer "B.SilkS")
		)
		(fp_line
			(start -0.7874 0.4064)
			(end 0.7874 0.4064)
			(stroke
				(width 0.1524)
				(type default)
			)
			(layer "B.SilkS")
		)
		(fp_line
			(start 0.67945 -0.305054)
			(end 0.12065 -0.305054)
			(stroke
				(width 0.1)
				(type default)
			)
			(layer "B.Fab")
		)
		(fp_line
			(start 0.12065 -0.305054)
			(end 0.12065 -0.2794)
			(stroke
				(width 0.1)
				(type default)
			)
			(layer "B.Fab")
		)
		(fp_line
			(start -0.12065 -0.3048)
			(end -0.67945 -0.3048)
			(stroke
				(width 0.1)
				(type default)
			)
			(layer "B.Fab")
		)
		(fp_line
			(start -0.67945 -0.3048)
			(end -0.67945 0.3048)
			(stroke
				(width 0.1)
				(type default)
			)
			(layer "B.Fab")
		)
		(fp_line
			(start 0.12065 -0.2794)
			(end -0.12065 -0.2794)
			(stroke
				(width 0.1)
				(type default)
			)
			(layer "B.Fab")
		)
		(fp_line
			(start -0.12065 -0.2794)
			(end -0.12065 -0.3048)
			(stroke
				(width 0.1)
				(type default)
			)
			(layer "B.Fab")
		)
		(fp_line
			(start 0.12065 0.2794)
			(end 0.12065 0.3048)
			(stroke
				(width 0.1)
				(type default)
			)
			(layer "B.Fab")
		)
		(fp_line
			(start -0.120396 0.2794)
			(end 0.12065 0.2794)
			(stroke
				(width 0.1)
				(type default)
			)
			(layer "B.Fab")
		)
		(fp_line
			(start 0.67945 0.3048)
			(end 0.67945 -0.305054)
			(stroke
				(width 0.1)
				(type default)
			)
			(layer "B.Fab")
		)
		(fp_line
			(start 0.12065 0.3048)
			(end 0.67945 0.3048)
			(stroke
				(width 0.1)
				(type default)
			)
			(layer "B.Fab")
		)
		(fp_line
			(start -0.120396 0.3048)
			(end -0.120396 0.2794)
			(stroke
				(width 0.1)
				(type default)
			)
			(layer "B.Fab")
		)
		(fp_line
			(start -0.67945 0.3048)
			(end -0.120396 0.3048)
			(stroke
				(width 0.1)
				(type default)
			)
			(layer "B.Fab")
		)
		(pad "1" smd circle
			(at 0.40005 0 270)
			(size 0 0)
			(layers "B.Cu" "B.Mask" "B.Paste")
			(net "P1V8_CPU1_RT3_1A")
		)
		(pad "2" smd circle
			(at -0.40005 0 270)
			(size 0 0)
			(layers "B.Cu" "B.Mask" "B.Paste")
			(net "GND")
		)
	)
)
